(kicad_pcb
	(version 20221018)
	(generator pcbnew)
	(general
    (thickness 1.518)
  )
	(paper "A4")
	(title_block
    (title "Kria K26 Devboard")
    (date "2024-03-26")
    (rev "1.2.5")
    (comment 1 "www.antmicro.com")
    (comment 2 "Antmicro Ltd.")
		(comment 9 "footprints 32-36 of 660")
	)
	(layers
    (0 "F.Cu" mixed)
    (1 "In1.Cu" power)
    (2 "In2.Cu" mixed)
    (3 "In3.Cu" power)
    (4 "In4.Cu" mixed)
    (5 "In5.Cu" power)
    (6 "In6.Cu" mixed)
    (31 "B.Cu" power)
    (32 "B.Adhes" user "B.Adhesive")
    (33 "F.Adhes" user "F.Adhesive")
    (34 "B.Paste" user)
    (35 "F.Paste" user)
    (36 "B.SilkS" user "B.Silkscreen")
    (37 "F.SilkS" user "F.Silkscreen")
    (38 "B.Mask" user)
    (39 "F.Mask" user)
    (40 "Dwgs.User" user "User.Drawings")
    (41 "Cmts.User" user "User.Comments")
    (42 "Eco1.User" user "User.Eco1")
    (43 "Eco2.User" user "User.Eco2")
    (44 "Edge.Cuts" user)
    (45 "Margin" user)
    (46 "B.CrtYd" user "B.Courtyard")
    (47 "F.CrtYd" user "F.Courtyard")
    (48 "B.Fab" user)
    (49 "F.Fab" user)
  )
	(footprint "kria-k26-devboard-footprints:Oscillator_SMD_ECS_2520MV_2.5x2mm" (layer "F.Cu")
    (at 109.025 96.3)
    (descr "Miniature Crystal Clock Oscillator ECS 2520MV series")
    (tags "Crystal Clock Oscillator ECS 2520MV SMD")
    (property "Author" "Antmicro")
    (property "License" "Apache-2.0")
    (property "MPN" "ECS-2520MVLC-260-CM-TR")
    (property "Manufacturer" "ECS Inc. International")
    (property "Sheetfile" "clock.kicad_sch")
    (property "Sheetname" "Clock distribution")
    (property "Val" "26 MHz")
    (property "ki_description" "Oscillator, 26 MHz, CMOS, 25 ppm, SMD, 2.5mm x 2mm, 3.6 V, MultiVolt ECS-2520MVLC Series")
    (property "ki_keywords" "OSCILLATOR")
    (attr smd)
    (fp_text reference "Y2" (at -0.705 -1.56) (layer "F.SilkS")
        (effects (font (size 0.7 0.7) (thickness 0.15)) (justify left bottom))
    )
    (fp_text value "Oscillator_26MHz_ESC_2520MV" (at 0 2.499) (layer "F.Fab") hide
        (effects (font (size 0.7 0.7) (thickness 0.15)) (justify left bottom))
    )
    (fp_text user "${REFERENCE}" (at -1.25 3.9) (layer "F.Fab") hide
        (effects (font (size 0.7 0.7) (thickness 0.15)) (justify left bottom))
    )
    (fp_text user "License: Apache-2.0" (at -1.25 6.302) (layer "F.Fab") hide
        (effects (font (size 0.7 0.7) (thickness 0.15)) (justify left bottom))
    )
    (fp_text user "Author: Antmicro" (at -1.25 5.102) (layer "F.Fab") hide
        (effects (font (size 0.7 0.7) (thickness 0.15)) (justify left bottom))
    )
    (fp_line (start -1.111 0.32) (end -1.111 -0.32)
      (stroke (width 0.15) (type solid)) (layer "F.SilkS"))
    (fp_line (start -0.172 1.36) (end 0.17 1.36)
      (stroke (width 0.15) (type solid)) (layer "F.SilkS"))
    (fp_line (start -0.16 -1.361) (end 0.17 -1.361)
      (stroke (width 0.15) (type solid)) (layer "F.SilkS"))
    (fp_line (start 1.11 0.32) (end 1.11 -0.32)
      (stroke (width 0.15) (type solid)) (layer "F.SilkS"))
    (fp_circle (center -1.1 -1.5) (end -1.049 -1.5)
      (stroke (width 0.15) (type solid)) (fill solid) (layer "F.SilkS"))
    (fp_rect (start -1.25 -1.5) (end 1.25 1.5)
      (stroke (width 0.05) (type solid)) (fill none) (layer "F.CrtYd"))
    (fp_line (start -1 -0.75) (end -0.5 -1.25)
      (stroke (width 0.15) (type solid)) (layer "F.Fab"))
    (fp_rect (start 1 1.249) (end -1 -1.25)
      (stroke (width 0.15) (type solid)) (fill none) (layer "F.Fab"))
    (pad "1" smd roundrect (at -0.725 -0.927) (size 0.8 0.9) (layers "F.Cu" "F.Paste" "F.Mask") (roundrect_rratio 0.25)
      (net 185 "/Clock distribution/PS_CLK_EN") (pinfunction "EN") (pintype "input"))
    (pad "2" smd roundrect (at -0.725 0.925) (size 0.8 0.9) (layers "F.Cu" "F.Paste" "F.Mask") (roundrect_rratio 0.25)
      (net 1 "GND") (pinfunction "GND") (pintype "power_in"))
    (pad "3" smd roundrect (at 0.723 0.925) (size 0.8 0.9) (layers "F.Cu" "F.Paste" "F.Mask") (roundrect_rratio 0.25)
      (net 698 "Net-(U8-IN)") (pinfunction "OUT") (pintype "output"))
    (pad "4" smd roundrect (at 0.723 -0.927) (size 0.8 0.9) (layers "F.Cu" "F.Paste" "F.Mask") (roundrect_rratio 0.25)
      (net 15 "PS_3V3") (pinfunction "VDD") (pintype "power_in"))
  )
	(footprint "kria-k26-devboard-footprints:SOIC-8-1EP_3.9x4.9x1.75mm_P1.27mm" (layer "F.Cu")
    (at 188.6 81.09 -90)
    (tags "Integrated Circuit")
    (property "Author" "Antmicro")
    (property "License" "Apache-2.0")
    (property "MPN" "TPS2378DDA")
    (property "Manufacturer" "Texas Instruments")
    (property "Sheetfile" "PoE.kicad_sch")
    (property "Sheetname" "PoE")
    (property "ki_description" "Power Over Ethernet (POE) Controller, 57 V/ 500 µA, 40 V UVLO Threshold, SOIC-8")
    (property "ki_keywords" "SMT, POE, IC, INTERFACE")
    (attr smd)
    (fp_text reference "IC1" (at 4.43 0.58) (layer "F.SilkS")
        (effects (font (size 0.7 0.7) (thickness 0.15)) (justify left bottom))
    )
    (fp_text value "TPS2378DDA" (at 0 3.65 -90) (layer "F.Fab")
        (effects (font (size 0.7 0.7) (thickness 0.15)) (justify left bottom))
    )
    (fp_text user "Author: Antmicro" (at -3.476 6.099 -90) (layer "F.Fab") hide
        (effects (font (size 0.7 0.7) (thickness 0.15)) (justify left bottom))
    )
    (fp_text user "${REFERENCE}" (at -3.476 7.099 -90) (layer "F.Fab") hide
        (effects (font (size 0.7 0.7) (thickness 0.15)) (justify left bottom))
    )
    (fp_text user "License: Apache-2.0" (at -3.476 5.099 -90) (layer "F.Fab") hide
        (effects (font (size 0.7 0.7) (thickness 0.15)) (justify left bottom))
    )
    (fp_line (start 1.95 -2.55) (end -1.95 -2.55)
      (stroke (width 0.15) (type solid)) (layer "F.SilkS"))
    (fp_line (start 1.95 2.55) (end -1.95 2.55)
      (stroke (width 0.15) (type solid)) (layer "F.SilkS"))
    (fp_circle (center -2.5 -2.45) (end -2.45 -2.4)
      (stroke (width 0.15) (type solid)) (fill solid) (layer "F.SilkS"))
    (fp_rect (start -3.55 -2.7) (end 3.55 2.7)
      (stroke (width 0.05) (type solid)) (fill none) (layer "F.CrtYd"))
    (fp_line (start -1.95 -1.18) (end -0.683 -2.452)
      (stroke (width 0.15) (type solid)) (layer "F.Fab"))
    (fp_line (start -1.95 2.45) (end -1.95 -1.18)
      (stroke (width 0.15) (type solid)) (layer "F.Fab"))
    (fp_line (start -0.683 -2.452) (end 1.949 -2.452)
      (stroke (width 0.15) (type solid)) (layer "F.Fab"))
    (fp_line (start 1.949 -2.452) (end 1.949 2.45)
      (stroke (width 0.15) (type solid)) (layer "F.Fab"))
    (fp_line (start 1.949 2.45) (end -1.95 2.45)
      (stroke (width 0.15) (type solid)) (layer "F.Fab"))
    (pad "1" smd roundrect (at -2.714 -1.905) (size 0.65 1.525) (layers "F.Cu" "F.Paste" "F.Mask") (roundrect_rratio 0.25)
      (net 9 "/Power Supply/PoE/VDD_POE_IN") (pinfunction "VDD") (pintype "power_in"))
    (pad "2" smd roundrect (at -2.714 -0.635) (size 0.65 1.525) (layers "F.Cu" "F.Paste" "F.Mask") (roundrect_rratio 0.25)
      (net 341 "Net-(IC1-DEN)") (pinfunction "DEN") (pintype "passive"))
    (pad "3" smd roundrect (at -2.714 0.632) (size 0.65 1.525) (layers "F.Cu" "F.Paste" "F.Mask") (roundrect_rratio 0.25)
      (net 342 "Net-(IC1-CLS)") (pinfunction "CLS") (pintype "passive"))
    (pad "4" smd roundrect (at -2.714 1.902) (size 0.65 1.525) (layers "F.Cu" "F.Paste" "F.Mask") (roundrect_rratio 0.25)
      (net 10 "/Power Supply/PoE/VSS_POE_IN") (pinfunction "VSS") (pintype "power_in"))
    (pad "5" smd roundrect (at 2.712 1.902) (size 0.65 1.525) (layers "F.Cu" "F.Paste" "F.Mask") (roundrect_rratio 0.25)
      (net 11 "GNDD") (pinfunction "RTN") (pintype "passive"))
    (pad "6" smd roundrect (at 2.712 0.632) (size 0.65 1.525) (layers "F.Cu" "F.Paste" "F.Mask") (roundrect_rratio 0.25)
      (net 12 "/Power Supply/PoE/POE_ACTIVE") (pinfunction "CDB") (pintype "passive"))
    (pad "7" smd roundrect (at 2.712 -0.635) (size 0.65 1.525) (layers "F.Cu" "F.Paste" "F.Mask") (roundrect_rratio 0.25)
      (net 343 "unconnected-(IC1-T2P-Pad7)") (pinfunction "T2P") (pintype "passive+no_connect"))
    (pad "8" smd roundrect (at 2.712 -1.905) (size 0.65 1.525) (layers "F.Cu" "F.Paste" "F.Mask") (roundrect_rratio 0.25)
      (net 11 "GNDD") (pinfunction "APD") (pintype "passive"))
    (pad "9" smd roundrect (at 0 0 270) (size 2.29 3.1) (layers "F.Cu" "F.Paste" "F.Mask") (roundrect_rratio 0.05)
      (net 10 "/Power Supply/PoE/VSS_POE_IN") (pinfunction "EP") (pintype "power_in"))
  )
	(footprint "kria-k26-devboard-footprints:R_0402_1005Metric" (layer "F.Cu")
    (at 189.75 76.75 180)
    (descr "Resistor SMD 0402")
    (tags "resistor SMD 0402")
    (property "Author" "Antmicro")
    (property "License" "Apache-2.0")
    (property "MPN" "CR0402-FX-2492GLF")
    (property "Manufacturer" "Bourns")
    (property "Sheetfile" "PoE.kicad_sch")
    (property "Sheetname" "PoE")
    (property "Tolerance" "1%")
    (property "Val" "24k9")
    (property "ki_description" "24k9 resistor in 0402 package with 1% tolerance")
    (attr smd)
    (fp_text reference "R115" (at 1.21 0.56 180) (layer "F.SilkS")
        (effects (font (size 0.7 0.7) (thickness 0.15)) (justify left bottom))
    )
    (fp_text value "R_24k9_0402" (at 0 1.4 180) (layer "F.Fab") hide
        (effects (font (size 0.7 0.7) (thickness 0.15)) (justify left bottom))
    )
    (fp_text user "${REFERENCE}" (at -0.95 3.168 180) (layer "F.Fab") hide
        (effects (font (size 0.7 0.7) (thickness 0.15)) (justify left bottom))
    )
    (fp_text user "Author: Antmicro" (at -0.95 4.169 180) (layer "F.Fab") hide
        (effects (font (size 0.7 0.7) (thickness 0.15)) (justify left bottom))
    )
    (fp_text user "License: Apache-2.0" (at -0.95 5.169 180) (layer "F.Fab") hide
        (effects (font (size 0.7 0.7) (thickness 0.15)) (justify left bottom))
    )
    (fp_rect (start -0.93 -0.47) (end 0.93 0.47)
      (stroke (width 0.05) (type solid)) (fill none) (layer "F.CrtYd"))
    (fp_rect (start -0.5 -0.25) (end 0.5 0.25)
      (stroke (width 0.15) (type solid)) (fill none) (layer "F.Fab"))
    (pad "1" smd roundrect (at -0.485 0 180) (size 0.59 0.64) (layers "F.Cu" "F.Paste" "F.Mask") (roundrect_rratio 0.25)
      (net 9 "/Power Supply/PoE/VDD_POE_IN") (pintype "passive"))
    (pad "2" smd roundrect (at 0.485 0 180) (size 0.59 0.64) (layers "F.Cu" "F.Paste" "F.Mask") (roundrect_rratio 0.25)
      (net 341 "Net-(IC1-DEN)") (pintype "passive"))
  )
	(footprint "kria-k26-devboard-footprints:C_2220_5650Metric" (layer "F.Cu")
    (at 182.87 82.95 90)
    (descr "Capacitor SMD 2220")
    (tags "capacitor SMD 2220")
    (property "Author" "Antmicro")
    (property "Dielectric" "")
    (property "License" "Apache-2.0")
    (property "MPN" "C5750X7S2A226M280KB")
    (property "Manufacturer" "TDK")
    (property "Sheetfile" "PoE.kicad_sch")
    (property "Sheetname" "PoE")
    (property "Val" "22u/100V")
    (property "Voltage" "")
    (property "ki_description" " ")
    (attr smd)
    (fp_text reference "C174" (at -1.39 -20.82 90) (layer "F.SilkS")
        (effects (font (size 0.7 0.7) (thickness 0.15)) (justify left bottom))
    )
    (fp_text value "C_22u_100V_2220" (at 0 3.9 90) (layer "F.Fab") hide
        (effects (font (size 0.7 0.7) (thickness 0.15)) (justify left bottom))
    )
    (fp_text user "Author: Antmicro" (at -3.7 7.9 90) (layer "F.Fab") hide
        (effects (font (size 0.7 0.7) (thickness 0.15)) (justify left bottom))
    )
    (fp_text user "${REFERENCE}" (at -3.7 5.9 90) (layer "F.Fab") hide
        (effects (font (size 0.7 0.7) (thickness 0.15)) (justify left bottom))
    )
    (fp_text user "License: Apache-2.0" (at -3.7 6.9 90) (layer "F.Fab") hide
        (effects (font (size 0.7 0.7) (thickness 0.15)) (justify left bottom))
    )
    (fp_line (start -1.415 -2.61) (end 1.415 -2.61)
      (stroke (width 0.15) (type solid)) (layer "F.SilkS"))
    (fp_line (start -1.415 2.61) (end 1.415 2.61)
      (stroke (width 0.15) (type solid)) (layer "F.SilkS"))
    (fp_rect (start -3.7 -2.95) (end 3.7 2.95)
      (stroke (width 0.05) (type solid)) (fill none) (layer "F.CrtYd"))
    (fp_rect (start -2.85 -2.5) (end 2.85 2.5)
      (stroke (width 0.15) (type solid)) (fill none) (layer "F.Fab"))
    (pad "1" smd roundrect (at -2.55 0 90) (size 1.8 5.4) (layers "F.Cu" "F.Paste" "F.Mask") (roundrect_rratio 0.138889)
      (net 9 "/Power Supply/PoE/VDD_POE_IN") (pintype "passive"))
    (pad "2" smd roundrect (at 2.55 0 90) (size 1.8 5.4) (layers "F.Cu" "F.Paste" "F.Mask") (roundrect_rratio 0.138889)
      (net 11 "GNDD") (pintype "passive"))
  )
	(footprint "kria-k26-devboard-footprints:C_0402_1005Metric" (layer "F.Cu")
    (at 149.5 60.74)
    (descr "Capacitor SMD 0402")
    (tags "capacitor SMD 0402")
    (property "Author" "Antmicro")
    (property "Dielectric" "")
    (property "License" "Apache-2.0")
    (property "MPN" "GRM155R71H104KE14D")
    (property "Manufacturer" "Murata")
    (property "Sheetfile" "usbc-socket.kicad_sch")
    (property "Sheetname" "USB-C socket")
    (property "Val" "100n/50V")
    (property "Voltage" "")
    (property "ki_description" " ")
    (attr smd)
    (fp_text reference "C231" (at 0.82 0.39) (layer "F.SilkS")
        (effects (font (size 0.7 0.7) (thickness 0.15)) (justify left bottom))
    )
    (fp_text value "C_100n_50V_0402" (at 0 1.4) (layer "F.Fab") hide
        (effects (font (size 0.7 0.7) (thickness 0.15)) (justify left bottom))
    )
    (fp_text user "Author: Antmicro" (at -0.932 4.17) (layer "F.Fab") hide
        (effects (font (size 0.7 0.7) (thickness 0.15)) (justify left bottom))
    )
    (fp_text user "License: Apache-2.0" (at -0.932 5.17) (layer "F.Fab") hide
        (effects (font (size 0.7 0.7) (thickness 0.15)) (justify left bottom))
    )
    (fp_text user "${REFERENCE}" (at -0.932 3.168) (layer "F.Fab") hide
        (effects (font (size 0.7 0.7) (thickness 0.15)) (justify left bottom))
    )
    (fp_rect (start -0.94 -0.47) (end 0.94 0.47)
      (stroke (width 0.05) (type solid)) (fill none) (layer "F.CrtYd"))
    (fp_rect (start -0.499 -0.249) (end 0.499 0.249)
      (stroke (width 0.15) (type solid)) (fill none) (layer "F.Fab"))
    (pad "1" smd roundrect (at -0.484 0) (size 0.59 0.64) (layers "F.Cu" "F.Paste" "F.Mask") (roundrect_rratio 0.25)
      (net 265 "/Debug and JTAG/USBC_VBUS") (pintype "passive"))
    (pad "2" smd roundrect (at 0.484 0) (size 0.59 0.64) (layers "F.Cu" "F.Paste" "F.Mask") (roundrect_rratio 0.25)
      (net 1 "GND") (pintype "passive"))
  )
)
